#ISCELL
  mstr_misc dns *
  *
#ISCELL
  mstr_misc prelim *
  *
#ISCELL
  mstr_symbols cad_note *
  *
#ISCELL
  mstr_symbols intel_corp_bpage *
  *
#ISCELL
  mstr_symbols gnd *
  page230_i10
#ISCELL
  mstr_symbols gnd *
  page230_i15
#CELL
  mstr_discrete cap *
  page230_i16
#CELL
  mstr_discrete res *
  page230_i17
#CELL
  mstr_discrete cap *
  page230_i18
#ISCELL
  mstr_symbols gnd *
  page230_i19
#CELL
  mstr_discrete cap *
  page230_i21
#ISCELL
  mstr_symbols gnd *
  page230_i22
#ISCELL
  mstr_symbols gnd *
  page230_i23
#ISCELL
  mstr_symbols gnd *
  page230_i24
#CELL
  mstr_discrete cap *
  page230_i25
#CELL
  mstr_discrete cap *
  page230_i26
#ISCELL
  mstr_symbols gnd *
  page230_i27
#CELL
  mstr_discrete cap *
  page230_i28
#ISCELL
  mstr_symbols gnd *
  page230_i29
#CELL
  mstr_discrete res *
  page230_i30
#CELL
  mstr_vreg mic5166 *
  page230_i31
#CELL
  mstr_discrete res *
  page230_i34
#ISCELL
  mstr_symbols pvddq_klm *
  page230_i35
#CELL
  mstr_discrete res *
  page230_i37
#CELL
  mstr_discrete res *
  page230_i38
#CELL
  mstr_discrete cap *
  page230_i39
#ISCELL
  mstr_symbols gnd *
  page230_i40
#ISCELL
  mstr_standard offpage *
  page230_i41
#ISCELL
  mstr_symbols p3v3 *
  page230_i42
#ISCELL
  mstr_symbols p3v3 *
  page230_i43
#ISCELL
  mstr_symbols gnd *
  page230_i45
#CELL
  mstr_discrete cap *
  page230_i46
#CELL
  dev_discrete cap_a *
  page230_i47
#CELL
  dev_discrete cap_a *
  page230_i48
#CELL
  dev_discrete cap_a *
  page230_i49
#CELL
  mstr_discrete res *
  page230_i51
#CELL
  mstr_discrete res *
  page230_i52
#CELL
  mstr_misc shunt *
  page230_i53
#ISCELL
  mstr_symbols pvtt_klm *
  page230_i6
#ISCELL
  mstr_standard offpage *
  page230_i8
#ISCELL
  mstr_symbols pvtt_klm *
  page230_i9
